# T6G (Grand Teton) — schematic netlist excerpt (pin names and nets, part order shuffled) for the footprints in the layout excerpt that follows; sources: Cadence DE-HDL packaged netlist, KiCad conversion of 04192023_DAF0TMB3IC0_F0TG_MB_C_brd_V02_OCP.brd

C2556  Q_CAP  22UF 4V 20% X6S  pkg C0402  page 70 : A = PVDDCR_SOC_P0 ; B = GND
C2491  Q_CAP  22UF 4V 20% X6S  pkg C0402  page 74 : A = PVDD11_S3_P1 ; B = GND

(kicad_pcb
	(version 20260206)
	(generator "pcbnew")
	(generator_version "10.0")
	(general
		(thickness 1.6)
		(legacy_teardrops no)
	)
	(paper "A4")
	(title_block
		(title "04192023_DAF0TMB3IC0_F0TG_MB_C_brd_V02_OCP.brd")
		(comment 1 "Grand Teton / footprints 7594-7595 of 8354")
	)
	(layers
		(0 "F.Cu" signal "TOP")
		(4 "In1.Cu" signal "GND")
		(6 "In2.Cu" signal "IN1")
		(8 "In3.Cu" signal "GND1")
		(10 "In4.Cu" signal "IN2")
		(12 "In5.Cu" signal "GND2")
		(14 "In6.Cu" signal "IN3")
		(16 "In7.Cu" signal "GND3")
		(18 "In8.Cu" signal "VCC")
		(20 "In9.Cu" signal "VCC1")
		(22 "In10.Cu" signal "GND4")
		(24 "In11.Cu" signal "IN4")
		(26 "In12.Cu" signal "GND5")
		(28 "In13.Cu" signal "IN5")
		(30 "In14.Cu" signal "GND6")
		(32 "In15.Cu" signal "IN6")
		(34 "In16.Cu" signal "GND7")
		(2 "B.Cu" signal "BOTTOM")
		(9 "F.Adhes" user "F.Adhesive")
		(11 "B.Adhes" user "B.Adhesive")
		(13 "F.Paste" user "Package Geometry/Pastemask Top")
		(15 "B.Paste" user "Package Geometry/Pastemask Bottom")
		(5 "F.SilkS" user "Ref Des/Silkscreen Top")
		(7 "B.SilkS" user "Ref Des/Silkscreen Bottom")
		(1 "F.Mask" user "Board Geometry/Soldermask Top")
		(3 "B.Mask" user "Board Geometry/Soldermask Bottom")
		(17 "Dwgs.User" user "User.Drawings")
		(19 "Cmts.User" user "User.Comments")
		(21 "Eco1.User" user "User.Eco1")
		(23 "Eco2.User" user "User.Eco2")
		(25 "Edge.Cuts" user "Board Geometry/Outline")
		(27 "Margin" user)
		(31 "F.CrtYd" user "Package Geometry/Place Bound Top")
		(29 "B.CrtYd" user "Package Geometry/Place Bound Bottom")
		(35 "F.Fab" user "Ref Des/Assembly Top")
		(33 "B.Fab" user "Ref Des/Assembly Bottom")
	)
	(footprint ""
		(layer "B.Cu")
		(at 113.376964 -261.748016 90)
		(property "Reference" "C2491"
			(at 0 0 90)
			(layer "B.SilkS")
			(hide yes)
			(effects
				(font
					(size 1.27 1.27)
				)
				(justify mirror)
			)
		)
		(property "Value" ""
			(at 0 0 90)
			(layer "B.Fab")
			(effects
				(font
					(size 1.27 1.27)
				)
				(justify mirror)
			)
		)
		(duplicate_pad_numbers_are_jumpers no)
		(fp_line
			(start 0.7874 -0.4064)
			(end -0.7874 -0.4064)
			(stroke
				(width 0.1524)
				(type default)
			)
			(layer "B.SilkS")
		)
		(fp_line
			(start -0.7874 -0.4064)
			(end -0.7874 0.4064)
			(stroke
				(width 0.1524)
				(type default)
			)
			(layer "B.SilkS")
		)
		(fp_line
			(start 0.7874 0.4064)
			(end 0.7874 -0.4064)
			(stroke
				(width 0.1524)
				(type default)
			)
			(layer "B.SilkS")
		)
		(fp_line
			(start -0.7874 0.4064)
			(end 0.7874 0.4064)
			(stroke
				(width 0.1524)
				(type default)
			)
			(layer "B.SilkS")
		)
		(fp_line
			(start 0.67945 -0.305054)
			(end 0.12065 -0.305054)
			(stroke
				(width 0.1)
				(type default)
			)
			(layer "B.Fab")
		)
		(fp_line
			(start 0.12065 -0.305054)
			(end 0.12065 -0.2794)
			(stroke
				(width 0.1)
				(type default)
			)
			(layer "B.Fab")
		)
		(fp_line
			(start -0.12065 -0.3048)
			(end -0.67945 -0.3048)
			(stroke
				(width 0.1)
				(type default)
			)
			(layer "B.Fab")
		)
		(fp_line
			(start -0.67945 -0.3048)
			(end -0.67945 0.3048)
			(stroke
				(width 0.1)
				(type default)
			)
			(layer "B.Fab")
		)
		(fp_line
			(start 0.12065 -0.2794)
			(end -0.12065 -0.2794)
			(stroke
				(width 0.1)
				(type default)
			)
			(layer "B.Fab")
		)
		(fp_line
			(start -0.12065 -0.2794)
			(end -0.12065 -0.3048)
			(stroke
				(width 0.1)
				(type default)
			)
			(layer "B.Fab")
		)
		(fp_line
			(start 0.12065 0.2794)
			(end 0.12065 0.3048)
			(stroke
				(width 0.1)
				(type default)
			)
			(layer "B.Fab")
		)
		(fp_line
			(start -0.120396 0.2794)
			(end 0.12065 0.2794)
			(stroke
				(width 0.1)
				(type default)
			)
			(layer "B.Fab")
		)
		(fp_line
			(start 0.67945 0.3048)
			(end 0.67945 -0.305054)
			(stroke
				(width 0.1)
				(type default)
			)
			(layer "B.Fab")
		)
		(fp_line
			(start 0.12065 0.3048)
			(end 0.67945 0.3048)
			(stroke
				(width 0.1)
				(type default)
			)
			(layer "B.Fab")
		)
		(fp_line
			(start -0.120396 0.3048)
			(end -0.120396 0.2794)
			(stroke
				(width 0.1)
				(type default)
			)
			(layer "B.Fab")
		)
		(fp_line
			(start -0.67945 0.3048)
			(end -0.120396 0.3048)
			(stroke
				(width 0.1)
				(type default)
			)
			(layer "B.Fab")
		)
		(pad "1" smd circle
			(at 0.40005 0 270)
			(size 0 0)
			(layers "B.Cu" "B.Mask" "B.Paste")
			(net "PVDD11_S3_P1")
		)
		(pad "2" smd circle
			(at -0.40005 0 270)
			(size 0 0)
			(layers "B.Cu" "B.Mask" "B.Paste")
			(net "GND")
		)
	)
	(footprint ""
		(layer "B.Cu")
		(at 361.645454 -253.43231)
		(property "Reference" "C2556"
			(at 0 0 0)
			(layer "B.SilkS")
			(hide yes)
			(effects
				(font
					(size 1.27 1.27)
				)
				(justify mirror)
			)
		)
		(property "Value" ""
			(at 0 0 0)
			(layer "B.Fab")
			(effects
				(font
					(size 1.27 1.27)
				)
				(justify mirror)
			)
		)
		(duplicate_pad_numbers_are_jumpers no)
		(fp_line
			(start -0.7874 -0.4064)
			(end -0.7874 0.4064)
			(stroke
				(width 0.1524)
				(type default)
			)
			(layer "B.SilkS")
		)
		(fp_line
			(start -0.7874 0.4064)
			(end 0.7874 0.4064)
			(stroke
				(width 0.1524)
				(type default)
			)
			(layer "B.SilkS")
		)
		(fp_line
			(start 0.7874 -0.4064)
			(end -0.7874 -0.4064)
			(stroke
				(width 0.1524)
				(type default)
			)
			(layer "B.SilkS")
		)
		(fp_line
			(start 0.7874 0.4064)
			(end 0.7874 -0.4064)
			(stroke
				(width 0.1524)
				(type default)
			)
			(layer "B.SilkS")
		)
		(fp_line
			(start -0.67945 -0.3048)
			(end -0.67945 0.3048)
			(stroke
				(width 0.1)
				(type default)
			)
			(layer "B.Fab")
		)
		(fp_line
			(start -0.67945 0.3048)
			(end -0.120396 0.3048)
			(stroke
				(width 0.1)
				(type default)
			)
			(layer "B.Fab")
		)
		(fp_line
			(start -0.12065 -0.3048)
			(end -0.67945 -0.3048)
			(stroke
				(width 0.1)
				(type default)
			)
			(layer "B.Fab")
		)
		(fp_line
			(start -0.12065 -0.2794)
			(end -0.12065 -0.3048)
			(stroke
				(width 0.1)
				(type default)
			)
			(layer "B.Fab")
		)
		(fp_line
			(start -0.120396 0.2794)
			(end 0.12065 0.2794)
			(stroke
				(width 0.1)
				(type default)
			)
			(layer "B.Fab")
		)
		(fp_line
			(start -0.120396 0.3048)
			(end -0.120396 0.2794)
			(stroke
				(width 0.1)
				(type default)
			)
			(layer "B.Fab")
		)
		(fp_line
			(start 0.12065 -0.305054)
			(end 0.12065 -0.2794)
			(stroke
				(width 0.1)
				(type default)
			)
			(layer "B.Fab")
		)
		(fp_line
			(start 0.12065 -0.2794)
			(end -0.12065 -0.2794)
			(stroke
				(width 0.1)
				(type default)
			)
			(layer "B.Fab")
		)
		(fp_line
			(start 0.12065 0.2794)
			(end 0.12065 0.3048)
			(stroke
				(width 0.1)
				(type default)
			)
			(layer "B.Fab")
		)
		(fp_line
			(start 0.12065 0.3048)
			(end 0.67945 0.3048)
			(stroke
				(width 0.1)
				(type default)
			)
			(layer "B.Fab")
		)
		(fp_line
			(start 0.67945 -0.305054)
			(end 0.12065 -0.305054)
			(stroke
				(width 0.1)
				(type default)
			)
			(layer "B.Fab")
		)
		(fp_line
			(start 0.67945 0.3048)
			(end 0.67945 -0.305054)
			(stroke
				(width 0.1)
				(type default)
			)
			(layer "B.Fab")
		)
		(pad "1" smd circle
			(at 0.40005 0 180)
			(size 0 0)
			(layers "B.Cu" "B.Mask" "B.Paste")
			(net "PVDDCR_SOC_P0")
		)
		(pad "2" smd circle
			(at -0.40005 0 180)
			(size 0 0)
			(layers "B.Cu" "B.Mask" "B.Paste")
			(net "GND")
		)
	)
)
